# T6G (Grand Teton) — schematic parts with pin connectivity, parts 8081–8081 of 8303; source: Cadence DE-HDL packaged netlist (pstxprt.dat, pstxnet.dat, pstchip.dat)

U25  GENOA_SP5  SOCKET6096_13568-001 IO  pkg SOCKET6096_93-4X120-45XA  page 10  (pins 4369-4704 of 6096)
  DA58  VSS_DA58  POWER  = GND
  DA59  MDB_DATA25  BI  = M_D_CPU0_SB_DQ<25>
  DA60  MDB_DATA26  BI  = M_D_CPU0_SB_DQ<26>
  DA61  VSS_DA61  POWER  = GND
  DA62  MBB_DATA25  BI  = M_B_CPU0_SB_DQ<25>
  DA63  VSS_DA63  POWER  = GND
  DA64  MBB_DATA26  BI  = M_B_CPU0_SB_DQ<26>
  DA65  VSS_DA65  POWER  = GND
  DA66  MFB_DATA25  BI  = M_F_CPU0_SB_DQ<25>
  DA67  MFB_DATA26  BI  = M_F_CPU0_SB_DQ<26>
  DA68  VSS_DA68  POWER  = GND
  DA69  MEB_DATA25  BI  = M_E_CPU0_SB_DQ<25>
  DA70  VSS_DA70  POWER  = GND
  DA71  MEB_DATA26  BI  = M_E_CPU0_SB_DQ<26>
  DA72  VSS_DA72  POWER  = GND
  DA73  MAB_DATA25  BI  = M_A_CPU0_SB_DQ<25>
  DA74  MAB_DATA26  BI  = M_A_CPU0_SB_DQ<26>
  DA75  VSS_DA75  POWER  = GND
  DB2  MGB_DQS_H3  BI  = M_G_CPU0_SB_DQS_DP<3>
  DB3  VSS_DB3  POWER  = GND
  DB4  MGB_DATA27  BI  = M_G_CPU0_SB_DQ<27>
  DB5  VDD_11_S3_DB5  POWER  = PVDD11_S3_P0
  DB6  MKB_DQS_H3  BI  = M_K_CPU0_SB_DQS_DP<3>
  DB7  MKB_DATA27  BI  = M_K_CPU0_SB_DQ<27>
  DB8  VSS_DB8  POWER  = GND
  DB9  MLB_DQS_H3  BI  = M_L_CPU0_SB_DQS_DP<3>
  DB10  VSS_DB10  POWER  = GND
  DB11  MLB_DATA27  BI  = M_L_CPU0_SB_DQ<27>
  DB12  VDD_11_S3_DB12  POWER  = PVDD11_S3_P0
  DB13  MHB_DQS_H3  BI  = M_H_CPU0_SB_DQS_DP<3>
  DB14  MHB_DATA27  BI  = M_H_CPU0_SB_DQ<27>
  DB15  VSS_DB15  POWER  = GND
  DB16  MJB_DQS_H3  BI  = M_J_CPU0_SB_DQS_DP<3>
  DB17  VSS_DB17  POWER  = GND
  DB18  MJB_DATA27  BI  = M_J_CPU0_SB_DQ<27>
  DB19  VDD_11_S3_DB19  POWER  = PVDD11_S3_P0
  DB20  MIB_DQS_H3  BI  = M_I_CPU0_SB_DQS_DP<3>
  DB21  MIB_DATA27  BI  = M_I_CPU0_SB_DQ<27>
  DB22  VSS_DB22  POWER  = GND
  DB23  VDDCR_CPU1_DB23  POWER  = PVDDCR_CPU1_P0
  DB24  VDDCR_CPU1_DB24  POWER  = PVDDCR_CPU1_P0
  DB25  VSS_DB25  POWER  = GND
  DB26  VDDCR_CPU1_DB26  POWER  = PVDDCR_CPU1_P0
  DB27  VDDCR_CPU1_DB27  POWER  = PVDDCR_CPU1_P0
  DB28  VSS_DB28  POWER  = GND
  DB29  VDDCR_CPU1_DB29  POWER  = PVDDCR_CPU1_P0
  DB30  VDDCR_CPU1_DB30  POWER  = PVDDCR_CPU1_P0
  DB31  VSS_DB31  POWER  = GND
  DB32  VDDCR_CPU1_DB32  POWER  = PVDDCR_CPU1_P0
  DB33  VDDCR_CPU1_DB33  POWER  = PVDDCR_CPU1_P0
  DB34  VSS_DB34  POWER  = GND
  DB35  P3_RXP2  IN  = P5E_CPU0_P3_RX_DP<2>
  DB36  P3_RXN2  IN  = P5E_CPU0_P3_RX_DN<2>
  DB37  VSS_DB37  POWER  = GND
  DB39  VSS_DB39  POWER  = GND
  DB40  P1_TXN13  OUT  = P5E_CPU0_P1_TX_DN<13>
  DB41  P1_TXP13  OUT  = P5E_CPU0_P1_TX_DP<13>
  DB42  VSS_DB42  POWER  = GND
  DB43  VDDCR_CPU1_DB43  POWER  = PVDDCR_CPU1_P0
  DB44  VDDCR_CPU1_DB44  POWER  = PVDDCR_CPU1_P0
  DB45  VSS_DB45  POWER  = GND
  DB46  VDDCR_CPU1_DB46  POWER  = PVDDCR_CPU1_P0
  DB47  VDDCR_CPU1_DB47  POWER  = PVDDCR_CPU1_P0
  DB48  VSS_DB48  POWER  = GND
  DB49  VDDCR_CPU1_DB49  POWER  = PVDDCR_CPU1_P0
  DB50  VDDCR_CPU1_DB50  POWER  = PVDDCR_CPU1_P0
  DB51  VSS_DB51  POWER  = GND
  DB52  VDDCR_CPU1_DB52  POWER  = PVDDCR_CPU1_P0
  DB53  VDDCR_CPU1_DB53  POWER  = PVDDCR_CPU1_P0
  DB54  VSS_DB54  POWER  = GND
  DB55  MCB_DATA27  BI  = M_C_CPU0_SB_DQ<27>
  DB56  MCB_DQS_H3  BI  = M_C_CPU0_SB_DQS_DP<3>
  DB57  VDDIO_DB57  POWER  = PVDDIO_P0
  DB58  MDB_DATA27  BI  = M_D_CPU0_SB_DQ<27>
  DB59  VSS_DB59  POWER  = GND
  DB60  MDB_DQS_H3  BI  = M_D_CPU0_SB_DQS_DP<3>
  DB61  VSS_DB61  POWER  = GND
  DB62  MBB_DATA27  BI  = M_B_CPU0_SB_DQ<27>
  DB63  MBB_DQS_H3  BI  = M_B_CPU0_SB_DQS_DP<3>
  DB64  VDDIO_DB64  POWER  = PVDDIO_P0
  DB65  MFB_DATA27  BI  = M_F_CPU0_SB_DQ<27>
  DB66  VSS_DB66  POWER  = GND
  DB67  MFB_DQS_H3  BI  = M_F_CPU0_SB_DQS_DP<3>
  DB68  VSS_DB68  POWER  = GND
  DB69  MEB_DATA27  BI  = M_E_CPU0_SB_DQ<27>
  DB70  MEB_DQS_H3  BI  = M_E_CPU0_SB_DQS_DP<3>
  DB71  VDDIO_DB71  POWER  = PVDDIO_P0
  DB72  MAB_DATA27  BI  = M_A_CPU0_SB_DQ<27>
  DB73  VSS_DB73  POWER  = GND
  DB74  MAB_DQS_H3  BI  = M_A_CPU0_SB_DQS_DP<3>
  DC1  VSS_DC1  POWER  = GND
  DC2  MGB_DQS_L3  BI  = M_G_CPU0_SB_DQS_DN<3>
  DC3  MGB_DQS_L8  BI  = M_G_CPU0_SB_DQS_DN<8>
  DC4  VSS_DC4  POWER  = GND
  DC5  MKB_DQS_L3  BI  = M_K_CPU0_SB_DQS_DN<3>
  DC6  VSS_DC6  POWER  = GND
  DC7  MKB_DQS_L8  BI  = M_K_CPU0_SB_DQS_DN<8>
  DC8  VSS_DC8  POWER  = GND
  DC9  MLB_DQS_L3  BI  = M_L_CPU0_SB_DQS_DN<3>
  DC10  MLB_DQS_L8  BI  = M_L_CPU0_SB_DQS_DN<8>
  DC11  VSS_DC11  POWER  = GND
  DC12  MHB_DQS_L3  BI  = M_H_CPU0_SB_DQS_DN<3>
  DC13  VSS_DC13  POWER  = GND
  DC14  MHB_DQS_L8  BI  = M_H_CPU0_SB_DQS_DN<8>
  DC15  VSS_DC15  POWER  = GND
  DC16  MJB_DQS_L3  BI  = M_J_CPU0_SB_DQS_DN<3>
  DC17  MJB_DQS_L8  BI  = M_J_CPU0_SB_DQS_DN<8>
  DC18  VSS_DC18  POWER  = GND
  DC19  MIB_DQS_L3  BI  = M_I_CPU0_SB_DQS_DN<3>
  DC20  VSS_DC20  POWER  = GND
  DC21  MIB_DQS_L8  BI  = M_I_CPU0_SB_DQS_DN<8>
  DC22  VSS_DC22  POWER  = GND
  DC23  P3_RXP13  IN  = P5E_CPU0_P3_RX_DP<13>
  DC24  P3_RXN13  IN  = P5E_CPU0_P3_RX_DN<13>
  DC25  VSS_DC25  POWER  = GND
  DC26  P3_RXP10  IN  = P5E_CPU0_P3_RX_DP<10>
  DC27  P3_RXN10  IN  = P5E_CPU0_P3_RX_DN<10>
  DC28  VSS_DC28  POWER  = GND
  DC29  P3_RXP7  IN  = P5E_CPU0_P3_RX_DP<7>
  DC30  P3_RXN7  IN  = P5E_CPU0_P3_RX_DN<7>
  DC31  VSS_DC31  POWER  = GND
  DC32  P3_RXP4  IN  = P5E_CPU0_P3_RX_DP<4>
  DC33  P3_RXN4  IN  = P5E_CPU0_P3_RX_DN<4>
  DC34  VSS_DC34  POWER  = GND
  DC35  VDDCR_CPU1_DC35  POWER  = PVDDCR_CPU1_P0
  DC36  VDDCR_CPU1_DC36  POWER  = PVDDCR_CPU1_P0
  DC40  VDDCR_CPU1_DC40  POWER  = PVDDCR_CPU1_P0
  DC41  VDDCR_CPU1_DC41  POWER  = PVDDCR_CPU1_P0
  DC42  VSS_DC42  POWER  = GND
  DC43  P1_TXN11  OUT  = P5E_CPU0_P1_TX_DN<11>
  DC44  P1_TXP11  OUT  = P5E_CPU0_P1_TX_DP<11>
  DC45  VSS_DC45  POWER  = GND
  DC46  P1_TXN8  OUT  = P5E_CPU0_P1_TX_DN<8>
  DC47  P1_TXP8  OUT  = P5E_CPU0_P1_TX_DP<8>
  DC48  VSS_DC48  POWER  = GND
  DC49  P1_TXN5  OUT  = P5E_CPU0_P1_TX_DN<5>
  DC50  P1_TXP5  OUT  = P5E_CPU0_P1_TX_DP<5>
  DC51  VSS_DC51  POWER  = GND
  DC52  P1_TXN2  OUT  = P5E_CPU0_P1_TX_DN<2>
  DC53  P1_TXP2  OUT  = P5E_CPU0_P1_TX_DP<2>
  DC54  VSS_DC54  POWER  = GND
  DC55  MCB_DQS_L8  BI  = M_C_CPU0_SB_DQS_DN<8>
  DC56  VSS_DC56  POWER  = GND
  DC57  MCB_DQS_L3  BI  = M_C_CPU0_SB_DQS_DN<3>
  DC58  VSS_DC58  POWER  = GND
  DC59  MDB_DQS_L8  BI  = M_D_CPU0_SB_DQS_DN<8>
  DC60  MDB_DQS_L3  BI  = M_D_CPU0_SB_DQS_DN<3>
  DC61  VSS_DC61  POWER  = GND
  DC62  MBB_DQS_L8  BI  = M_B_CPU0_SB_DQS_DN<8>
  DC63  VSS_DC63  POWER  = GND
  DC64  MBB_DQS_L3  BI  = M_B_CPU0_SB_DQS_DN<3>
  DC65  VSS_DC65  POWER  = GND
  DC66  MFB_DQS_L8  BI  = M_F_CPU0_SB_DQS_DN<8>
  DC67  MFB_DQS_L3  BI  = M_F_CPU0_SB_DQS_DN<3>
  DC68  VSS_DC68  POWER  = GND
  DC69  MEB_DQS_L8  BI  = M_E_CPU0_SB_DQS_DN<8>
  DC70  VSS_DC70  POWER  = GND
  DC71  MEB_DQS_L3  BI  = M_E_CPU0_SB_DQS_DN<3>
  DC72  VSS_DC72  POWER  = GND
  DC73  MAB_DQS_L8  BI  = M_A_CPU0_SB_DQS_DN<8>
  DC74  MAB_DQS_L3  BI  = M_A_CPU0_SB_DQS_DN<3>
  DC75  VSS_DC75  POWER  = GND
  DD2  MGB_DATA28  BI  = M_G_CPU0_SB_DQ<28>
  DD3  VSS_DD3  POWER  = GND
  DD4  MGB_DQS_H8  BI  = M_G_CPU0_SB_DQS_DP<8>
  DD5  VSS_DD5  POWER  = GND
  DD6  MKB_DATA28  BI  = M_K_CPU0_SB_DQ<28>
  DD7  MKB_DQS_H8  BI  = M_K_CPU0_SB_DQS_DP<8>
  DD8  VSS_DD8  POWER  = GND
  DD9  MLB_DATA28  BI  = M_L_CPU0_SB_DQ<28>
  DD10  VSS_DD10  POWER  = GND
  DD11  MLB_DQS_H8  BI  = M_L_CPU0_SB_DQS_DP<8>
  DD12  VSS_DD12  POWER  = GND
  DD13  MHB_DATA28  BI  = M_H_CPU0_SB_DQ<28>
  DD14  MHB_DQS_H8  BI  = M_H_CPU0_SB_DQS_DP<8>
  DD15  VSS_DD15  POWER  = GND
  DD16  MJB_DATA28  BI  = M_J_CPU0_SB_DQ<28>
  DD17  VSS_DD17  POWER  = GND
  DD18  MJB_DQS_H8  BI  = M_J_CPU0_SB_DQS_DP<8>
  DD19  VSS_DD19  POWER  = GND
  DD20  MIB_DATA28  BI  = M_I_CPU0_SB_DQ<28>
  DD21  MIB_DQS_H8  BI  = M_I_CPU0_SB_DQS_DP<8>
  DD22  VDDCR_CPU1_DD22  POWER  = PVDDCR_CPU1_P0
  DD23  VSS_DD23  POWER  = GND
  DD24  VSS_DD24  POWER  = GND
  DD25  VDDCR_CPU1_DD25  POWER  = PVDDCR_CPU1_P0
  DD26  VSS_DD26  POWER  = GND
  DD27  VSS_DD27  POWER  = GND
  DD28  VDDCR_CPU1_DD28  POWER  = PVDDCR_CPU1_P0
  DD29  VSS_DD29  POWER  = GND
  DD30  VSS_DD30  POWER  = GND
  DD31  VDDCR_CPU1_DD31  POWER  = PVDDCR_CPU1_P0
  DD32  VSS_DD32  POWER  = GND
  DD33  VSS_DD33  POWER  = GND
  DD34  VDDCR_CPU1_DD34  POWER  = PVDDCR_CPU1_P0
  DD35  VSS_DD35  POWER  = GND
  DD36  VSS_DD36  POWER  = GND
  DD37  VSS_DD37  POWER  = GND
  DD39  VSS_DD39  POWER  = GND
  DD40  VSS_DD40  POWER  = GND
  DD41  VSS_DD41  POWER  = GND
  DD42  VDDCR_CPU1_DD42  POWER  = PVDDCR_CPU1_P0
  DD43  VSS_DD43  POWER  = GND
  DD44  VSS_DD44  POWER  = GND
  DD45  VDDCR_CPU1_DD45  POWER  = PVDDCR_CPU1_P0
  DD46  VSS_DD46  POWER  = GND
  DD47  VSS_DD47  POWER  = GND
  DD48  VDDCR_CPU1_DD48  POWER  = PVDDCR_CPU1_P0
  DD49  VSS_DD49  POWER  = GND
  DD50  VSS_DD50  POWER  = GND
  DD51  VDDCR_CPU1_DD51  POWER  = PVDDCR_CPU1_P0
  DD52  VSS_DD52  POWER  = GND
  DD53  VSS_DD53  POWER  = GND
  DD54  VDDCR_CPU1_DD54  POWER  = PVDDCR_CPU1_P0
  DD55  MCB_DQS_H8  BI  = M_C_CPU0_SB_DQS_DP<8>
  DD56  MCB_DATA28  BI  = M_C_CPU0_SB_DQ<28>
  DD57  VSS_DD57  POWER  = GND
  DD58  MDB_DQS_H8  BI  = M_D_CPU0_SB_DQS_DP<8>
  DD59  VSS_DD59  POWER  = GND
  DD60  MDB_DATA28  BI  = M_D_CPU0_SB_DQ<28>
  DD61  VSS_DD61  POWER  = GND
  DD62  MBB_DQS_H8  BI  = M_B_CPU0_SB_DQS_DP<8>
  DD63  MBB_DATA28  BI  = M_B_CPU0_SB_DQ<28>
  DD64  VSS_DD64  POWER  = GND
  DD65  MFB_DQS_H8  BI  = M_F_CPU0_SB_DQS_DP<8>
  DD66  VSS_DD66  POWER  = GND
  DD67  MFB_DATA28  BI  = M_F_CPU0_SB_DQ<28>
  DD68  VSS_DD68  POWER  = GND
  DD69  MEB_DQS_H8  BI  = M_E_CPU0_SB_DQS_DP<8>
  DD70  MEB_DATA28  BI  = M_E_CPU0_SB_DQ<28>
  DD71  VSS_DD71  POWER  = GND
  DD72  MAB_DQS_H8  BI  = M_A_CPU0_SB_DQS_DP<8>
  DD73  VSS_DD73  POWER  = GND
  DD74  MAB_DATA28  BI  = M_A_CPU0_SB_DQ<28>
  DE1  VSS_DE1  POWER  = GND
  DE2  MGB_DATA30  BI  = M_G_CPU0_SB_DQ<30>
  DE3  MGB_DATA29  BI  = M_G_CPU0_SB_DQ<29>
  DE4  VDD_11_S3_DE4  POWER  = PVDD11_S3_P0
  DE5  MKB_DATA30  BI  = M_K_CPU0_SB_DQ<30>
  DE6  VSS_DE6  POWER  = GND
  DE7  MKB_DATA29  BI  = M_K_CPU0_SB_DQ<29>
  DE8  VSS_DE8  POWER  = GND
  DE9  MLB_DATA30  BI  = M_L_CPU0_SB_DQ<30>
  DE10  MLB_DATA29  BI  = M_L_CPU0_SB_DQ<29>
  DE11  VDD_11_S3_DE11  POWER  = PVDD11_S3_P0
  DE12  MHB_DATA30  BI  = M_H_CPU0_SB_DQ<30>
  DE13  VSS_DE13  POWER  = GND
  DE14  MHB_DATA29  BI  = M_H_CPU0_SB_DQ<29>
  DE15  VSS_DE15  POWER  = GND
  DE16  MJB_DATA30  BI  = M_J_CPU0_SB_DQ<30>
  DE17  MJB_DATA29  BI  = M_J_CPU0_SB_DQ<29>
  DE18  VDD_11_S3_DE18  POWER  = PVDD11_S3_P0
  DE19  MIB_DATA30  BI  = M_I_CPU0_SB_DQ<30>
  DE20  VSS_DE20  POWER  = GND
  DE21  MIB_DATA29  BI  = M_I_CPU0_SB_DQ<29>
  DE22  VDDCR_CPU1_DE22  POWER  = PVDDCR_CPU1_P0
  DE23  VSS_DE23  POWER  = GND
  DE24  \espi1_dat1||spi1_dat1||agpio132\  BI  = ESPI_CPU0_R_D1
  DE25  VDDCR_CPU1_DE25  POWER  = PVDDCR_CPU1_P0
  DE26  VSS_DE26  POWER  = GND
  DE27  \espi_rstout_l||agpio23\  BI  = RST_ESPI_CPU0_R_RSTOUT_N
  DE28  VDDCR_CPU1_DE28  POWER  = PVDDCR_CPU1_P0
  DE29  VSS_DE29  POWER  = GND
  DE30  AGPIO105  BI  = BIOS_DEBUG_MODE
  DE31  VDDCR_CPU1_DE31  POWER  = PVDDCR_CPU1_P0
  DE32  AGPIO22  BI  = FM_BOARD_SKU_ID1
  DE33  VSS_DE33  POWER  = GND
  DE34  VDDCR_CPU1_DE34  POWER  = PVDDCR_CPU1_P0
  DE35  VDDCR_CPU1_DE35  POWER  = PVDDCR_CPU1_P0
  DE36  \agpio3||spd_host_ctrl_l\  BI  = CPU0_SPD_HOST_CTRL_N
  DE40  \agpio6||devslp1||sata_zp1_l\  BI  = IRQ_BMC_SMI_N
  DE41  VDDCR_CPU1_DE41  POWER  = PVDDCR_CPU1_P0
  DE42  VDDCR_CPU1_DE42  POWER  = PVDDCR_CPU1_P0
  DE43  P4_TXN3  OUT  = P3E_CPU0_P4_TX_DN<3>
  DE44  P4_TXP3  OUT  = P3E_CPU0_P4_TX_DP<3>
  DE45  VDDCR_CPU1_DE45  POWER  = PVDDCR_CPU1_P0
  DE46  P4_TXN2  OUT  = P3E_CPU0_P4_TX_DN<2>
  DE47  P4_TXP2  OUT  = P3E_CPU0_P4_TX_DP<2>
  DE48  VDDCR_CPU1_DE48  POWER  = PVDDCR_CPU1_P0
  DE49  P4_TXN1  OUT  = P3E_CPU0_P4_TX_DN<1>
  DE50  P4_TXP1  OUT  = P3E_CPU0_P4_TX_DP<1>
  DE51  VDDCR_CPU1_DE51  POWER  = PVDDCR_CPU1_P0
  DE52  P4_TXN0  OUT  = P3E_CPU0_P4_TX_DN<0>
  DE53  P4_TXP0  OUT  = P3E_CPU0_P4_TX_DP<0>
  DE54  VDDCR_CPU1_DE54  POWER  = PVDDCR_CPU1_P0
  DE55  MCB_DATA29  BI  = M_C_CPU0_SB_DQ<29>
  DE56  VSS_DE56  POWER  = GND
  DE57  MCB_DATA30  BI  = M_C_CPU0_SB_DQ<30>
  DE58  VDDIO_DE58  POWER  = PVDDIO_P0
  DE59  MDB_DATA29  BI  = M_D_CPU0_SB_DQ<29>
  DE60  MDB_DATA30  BI  = M_D_CPU0_SB_DQ<30>
  DE61  VSS_DE61  POWER  = GND
  DE62  MBB_DATA29  BI  = M_B_CPU0_SB_DQ<29>
  DE63  VSS_DE63  POWER  = GND
  DE64  MBB_DATA30  BI  = M_B_CPU0_SB_DQ<30>
  DE65  VDDIO_DE65  POWER  = PVDDIO_P0
  DE66  MFB_DATA29  BI  = M_F_CPU0_SB_DQ<29>
  DE67  MFB_DATA30  BI  = M_F_CPU0_SB_DQ<30>
  DE68  VSS_DE68  POWER  = GND
  DE69  MEB_DATA29  BI  = M_E_CPU0_SB_DQ<29>
  DE70  VSS_DE70  POWER  = GND
  DE71  MEB_DATA30  BI  = M_E_CPU0_SB_DQ<30>
  DE72  VDDIO_DE72  POWER  = PVDDIO_P0
  DE73  MAB_DATA29  BI  = M_A_CPU0_SB_DQ<29>
  DE74  MAB_DATA30  BI  = M_A_CPU0_SB_DQ<30>
  DE75  VSS_DE75  POWER  = GND
  DF2  MGB_DATA31  BI  = M_G_CPU0_SB_DQ<31>
  DF3  VSS_DF3  POWER  = GND
  DF4  VSS_DF4  POWER  = GND
  DF5  VSS_DF5  POWER  = GND
  DF6  VSS_DF6  POWER  = GND
  DF7  MKB_DATA31  BI  = M_K_CPU0_SB_DQ<31>
  DF8  VSS_DF8  POWER  = GND
  DF9  MLB_DATA31  BI  = M_L_CPU0_SB_DQ<31>
  DF10  VSS_DF10  POWER  = GND
  DF11  VSS_DF11  POWER  = GND
  DF12  VSS_DF12  POWER  = GND
  DF13  VSS_DF13  POWER  = GND
  DF14  MHB_DATA31  BI  = M_H_CPU0_SB_DQ<31>
  DF15  VSS_DF15  POWER  = GND
  DF16  MJB_DATA31  BI  = M_J_CPU0_SB_DQ<31>
  DF17  VSS_DF17  POWER  = GND
  DF18  VSS_DF18  POWER  = GND
  DF19  VSS_DF19  POWER  = GND
  DF20  VSS_DF20  POWER  = GND
  DF21  MIB_DATA31  BI  = M_I_CPU0_SB_DQ<31>
  DF22  VSS_DF22  POWER  = GND
  DF23  VSS_DF23  POWER  = GND
  DF24  \espi1_alert_l||agpio110\  BI  = ESPI_CPU0_R_ALERT_N
  DF25  \espi1_dat2||spi1_dat2||agpio133\  BI  = ESPI_CPU0_R_D2
  DF26  VSS_DF26  POWER  = GND
  DF27  \espi_clk2||agpio74\  BI  = PD_ESPI_CPU0_CLK2
  DF28  \espi0_dat0||spi0_dat0||agpio120\  BI  = SPI_CPU0_R_D0
  DF29  VSS_DF29  POWER  = GND
  DF30  \spi_cs0_l||agpio118\  BI  = SPI_CPU0_R_CS0_N
  DF31  AGPIO106  BI  = FM_BOARD_SKU_ID2
